# TIMECARD (Time Appliance Project (Time Card)) — schematic netlist excerpt (pin names and nets, part order shuffled) for the footprints in the layout excerpt that follows; sources: Cadence DE-HDL packaged netlist, KiCad conversion of R4006-B0001-02_R01.brd

U20  ISL80101IRAJZ_DFN10  pkg DFN11_118_P0197_TR057X071  page 30
  VOUT_1  = XP1R2V_FPGA
  VOUT_2  = XP1R2V_FPGA
  \sense/adj\  = XP1R2V_FB
  PG  = XP1R2V_PG_R
  GND  = SG
  SS  = XP1R2V_SS
  ENABLE  = XP1R2V_EN_R
  NC  = NC
  VIN_1  = XP1R2V_VIN
  VIN_2  = XP1R2V_VIN
  THRM_PAD  = SG

(kicad_pcb
	(version 20260206)
	(generator "pcbnew")
	(generator_version "10.0")
	(general
		(thickness 1.6)
		(legacy_teardrops no)
	)
	(paper "A4")
	(title_block
		(title "timecard-production-celestica-r4006 — R4006-B0001-02_R01.brd")
		(comment 1 "Time Appliance Project (Time Card) / footprints 96-96 of 1113")
	)
	(layers
		(0 "F.Cu" signal "TOP")
		(4 "In1.Cu" signal "L02_GND1")
		(6 "In2.Cu" signal "L03_SIG1")
		(8 "In3.Cu" signal "L04_GND2")
		(10 "In4.Cu" signal "L05_VCC1")
		(12 "In5.Cu" signal "L06_VCC2")
		(14 "In6.Cu" signal "L07_GND3")
		(16 "In7.Cu" signal "L08_SIG2")
		(18 "In8.Cu" signal "L09_GND4")
		(2 "B.Cu" signal "BOTTOM")
		(9 "F.Adhes" user "F.Adhesive")
		(11 "B.Adhes" user "B.Adhesive")
		(13 "F.Paste" user "Package Geometry/Pastemask Top")
		(15 "B.Paste" user "Package Geometry/Pastemask Bottom")
		(5 "F.SilkS" user "Ref Des/Silkscreen Top")
		(7 "B.SilkS" user "Ref Des/Silkscreen Bottom")
		(1 "F.Mask" user "Board Geometry/Soldermask Top")
		(3 "B.Mask" user "Board Geometry/Soldermask Bottom")
		(17 "Dwgs.User" user "User.Drawings")
		(19 "Cmts.User" user "User.Comments")
		(21 "Eco1.User" user "User.Eco1")
		(23 "Eco2.User" user "User.Eco2")
		(25 "Edge.Cuts" user "Board Geometry/Outline")
		(27 "Margin" user)
		(31 "F.CrtYd" user "Package Geometry/Place Bound Top")
		(29 "B.CrtYd" user "Package Geometry/Place Bound Bottom")
		(35 "F.Fab" user "Ref Des/Assembly Top")
		(33 "B.Fab" user "Ref Des/Assembly Bottom")
	)
	(footprint ""
		(layer "F.Cu")
		(at 99.3648 -74.803 90)
		(property "Reference" "U20"
			(at 0 2.65557 90)
			(unlocked yes)
			(layer "F.SilkS")
			(effects
				(font
					(size 0.7874 0.5842)
					(thickness 0.1524)
				)
			)
		)
		(property "Value" ""
			(at 0 0 90)
			(layer "F.Fab")
			(effects
				(font
					(size 1.27 1.27)
				)
			)
		)
		(property "Device Type" "ISL80101IRAJZ_DFN10-G222-10136A"
			(at 0.276606 2.583688 90)
			(unlocked yes)
			(layer "F.Fab")
			(hide yes)
			(effects
				(font
					(size 0.7874 0.5842)
					(thickness 0.1524)
				)
			)
		)
		(property "User Part Number" "PARTNUM*"
			(at 0.276606 3.517646 90)
			(unlocked yes)
			(layer "Cmts.User")
			(hide yes)
			(effects
				(font
					(size 0.7874 0.5842)
					(thickness 0.1524)
				)
			)
		)
		(duplicate_pad_numbers_are_jumpers no)
		(fp_line
			(start 2.290318 -1.779016)
			(end 2.290318 1.779016)
			(stroke
				(width 0.1)
				(type default)
			)
			(layer "F.SilkS")
		)
		(fp_line
			(start -2.290318 -1.779016)
			(end 2.290318 -1.779016)
			(stroke
				(width 0.1)
				(type default)
			)
			(layer "F.SilkS")
		)
		(fp_line
			(start 2.290318 1.779016)
			(end -2.290318 1.779016)
			(stroke
				(width 0.1)
				(type default)
			)
			(layer "F.SilkS")
		)
		(fp_line
			(start -2.290318 1.779016)
			(end -2.290318 -1.779016)
			(stroke
				(width 0.1)
				(type default)
			)
			(layer "F.SilkS")
		)
		(fp_poly
			(pts
				(arc
					(start -2.934462 -0.642112)
					(mid -2.934462 -1.404112)
					(end -2.934462 -0.642112)
				)
			)
			(stroke
				(width 0)
				(type default)
			)
			(fill yes)
			(layer "F.SilkS")
		)
		(fp_rect
			(start -0.7239 0.9017)
			(end 0.7239 0.1016)
			(stroke
				(width 0)
				(type default)
			)
			(fill yes)
			(layer "F.Paste")
		)
		(fp_poly
			(pts
				(xy -0.7239 -0.1016)
				(arc
					(start -0.7239 -0.6477)
					(mid -0.290295 -0.468095)
					(end -0.4699 -0.9017)
				)
				(xy 0.7239 -0.9017) (xy 0.7239 -0.1016)
			)
			(stroke
				(width 0)
				(type default)
			)
			(fill yes)
			(layer "F.Paste")
		)
		(fp_poly
			(pts
				(xy -2.544318 2.033016) (xy 2.544318 2.033016) (xy 2.544318 -2.033016) (xy -2.544318 -2.033016)
			)
			(stroke
				(width 0)
				(type default)
			)
			(fill no)
			(layer "F.CrtYd")
		)
		(fp_line
			(start 1.525016 -1.525016)
			(end 1.525016 1.525016)
			(stroke
				(width 0.1)
				(type default)
			)
			(layer "F.Fab")
		)
		(fp_line
			(start -1.525016 -1.525016)
			(end 1.525016 -1.525016)
			(stroke
				(width 0.1)
				(type default)
			)
			(layer "F.Fab")
		)
		(fp_line
			(start 1.525016 1.525016)
			(end -1.525016 1.525016)
			(stroke
				(width 0.1)
				(type default)
			)
			(layer "F.Fab")
		)
		(fp_line
			(start -1.525016 1.525016)
			(end -1.525016 -1.525016)
			(stroke
				(width 0.1)
				(type default)
			)
			(layer "F.Fab")
		)
		(fp_poly
			(pts
				(arc
					(start -2.934462 -0.642112)
					(mid -2.934462 -1.404112)
					(end -2.934462 -0.642112)
				)
			)
			(stroke
				(width 0)
				(type default)
			)
			(fill yes)
			(layer "F.Fab")
		)
		(fp_text user "5"
			(at -2.825496 1.115822 90)
			(unlocked yes)
			(layer "F.SilkS")
			(effects
				(font
					(size 0.7874 0.5842)
					(thickness 0.1524)
				)
			)
		)
		(fp_text user "6"
			(at 2.24663 2.2352 0)
			(unlocked yes)
			(layer "F.SilkS")
			(effects
				(font
					(size 0.7874 0.5842)
					(thickness 0.1524)
				)
			)
		)
		(fp_text user "10"
			(at 2.38633 -1.3208 0)
			(unlocked yes)
			(layer "F.Fab")
			(effects
				(font
					(size 0.7874 0.5842)
					(thickness 0.1524)
				)
			)
		)
		(fp_text user "6"
			(at 2.38633 0.8382 0)
			(unlocked yes)
			(layer "F.Fab")
			(effects
				(font
					(size 0.7874 0.5842)
					(thickness 0.1524)
				)
			)
		)
		(fp_text user "5"
			(at -1.67767 1.9812 0)
			(unlocked yes)
			(layer "F.Fab")
			(effects
				(font
					(size 0.7874 0.5842)
					(thickness 0.1524)
				)
			)
		)
		(pad "1" smd circle
			(at -1.515618 -1.000252 270)
			(size 0 0)
			(layers "F.Cu" "F.Mask" "F.Paste")
			(net "XP1R2V_FPGA")
		)
		(pad "2" smd rect
			(at -1.515618 -0.500126 90)
			(size 1.0414 0.3048)
			(layers "F.Cu" "F.Mask" "F.Paste")
			(net "XP1R2V_FPGA")
		)
		(pad "3" smd rect
			(at -1.515618 0 90)
			(size 1.0414 0.3048)
			(layers "F.Cu" "F.Mask" "F.Paste")
			(net "XP1R2V_FB")
		)
		(pad "4" smd rect
			(at -1.515618 0.500126 90)
			(size 1.0414 0.3048)
			(layers "F.Cu" "F.Mask" "F.Paste")
			(net "XP1R2V_PG_R")
		)
		(pad "5" smd circle
			(at -1.515618 1.000252 90)
			(size 0 0)
			(layers "F.Cu" "F.Mask" "F.Paste")
			(net "SG")
		)
		(pad "6" smd circle
			(at 1.515618 1.000252 90)
			(size 0 0)
			(layers "F.Cu" "F.Mask" "F.Paste")
			(net "XP1R2V_SS")
		)
		(pad "7" smd rect
			(at 1.515618 0.500126 90)
			(size 1.0414 0.3048)
			(layers "F.Cu" "F.Mask" "F.Paste")
			(net "XP1R2V_EN_R")
		)
		(pad "8" smd rect
			(at 1.515618 0 90)
			(size 1.0414 0.3048)
			(layers "F.Cu" "F.Mask" "F.Paste")
			(net "Net_766")
		)
		(pad "9" smd rect
			(at 1.515618 -0.500126 90)
			(size 1.0414 0.3048)
			(layers "F.Cu" "F.Mask" "F.Paste")
			(net "XP1R2V_VIN")
		)
		(pad "10" smd circle
			(at 1.515618 -1.000252 270)
			(size 0 0)
			(layers "F.Cu" "F.Mask" "F.Paste")
			(net "XP1R2V_VIN")
		)
		(pad "11" smd rect
			(at 0 0 90)
			(size 1.4478 1.8034)
			(layers "F.Cu" "F.Mask" "F.Paste")
			(net "SG")
		)
	)
)
